(kicad_pcb
	(version 20260206)
	(generator "pcbnew")
	(generator_version "10.0")
	(general
		(thickness 1.6)
		(legacy_teardrops no)
	)
	(paper "A4")
	(title_block
		(title "04192023_DAF0TMB3IC0_F0TG_MB_C_brd_V02_OCP.brd")
		(comment 1 "Grand Teton / footprint 3955 of 8354 (U25), pads 3555-3667 of 6102")
	)
	(layers
		(0 "F.Cu" signal "TOP")
		(4 "In1.Cu" signal "GND")
		(6 "In2.Cu" signal "IN1")
		(8 "In3.Cu" signal "GND1")
		(10 "In4.Cu" signal "IN2")
		(12 "In5.Cu" signal "GND2")
		(14 "In6.Cu" signal "IN3")
		(16 "In7.Cu" signal "GND3")
		(18 "In8.Cu" signal "VCC")
		(20 "In9.Cu" signal "VCC1")
		(22 "In10.Cu" signal "GND4")
		(24 "In11.Cu" signal "IN4")
		(26 "In12.Cu" signal "GND5")
		(28 "In13.Cu" signal "IN5")
		(30 "In14.Cu" signal "GND6")
		(32 "In15.Cu" signal "IN6")
		(34 "In16.Cu" signal "GND7")
		(2 "B.Cu" signal "BOTTOM")
		(9 "F.Adhes" user "F.Adhesive")
		(11 "B.Adhes" user "B.Adhesive")
		(13 "F.Paste" user "Package Geometry/Pastemask Top")
		(15 "B.Paste" user "Package Geometry/Pastemask Bottom")
		(5 "F.SilkS" user "Ref Des/Silkscreen Top")
		(7 "B.SilkS" user "Ref Des/Silkscreen Bottom")
		(1 "F.Mask" user "Board Geometry/Soldermask Top")
		(3 "B.Mask" user "Board Geometry/Soldermask Bottom")
		(17 "Dwgs.User" user "User.Drawings")
		(19 "Cmts.User" user "User.Comments")
		(21 "Eco1.User" user "User.Eco1")
		(23 "Eco2.User" user "User.Eco2")
		(25 "Edge.Cuts" user "Board Geometry/Outline")
		(27 "Margin" user)
		(31 "F.CrtYd" user "Package Geometry/Place Bound Top")
		(29 "B.CrtYd" user "Package Geometry/Place Bound Bottom")
		(35 "F.Fab" user "Ref Des/Assembly Top")
		(33 "B.Fab" user "Ref Des/Assembly Bottom")
	)
	(footprint ""
		(layer "F.Cu")
		(at 359.867962 -258.880102 180)
		(property "Reference" "U25"
			(at -45.78477 -62.086744 0)
			(unlocked yes)
			(layer "F.SilkS")
			(effects
				(font
					(size 0.7874 0.5842)
					(thickness 0.1524)
				)
			)
		)
		(property "Value" ""
			(at 0 0 180)
			(layer "F.Fab")
			(effects
				(font
					(size 1.27 1.27)
				)
			)
		)
		(duplicate_pad_numbers_are_jumpers no)
		(pad "CL27" smd circle
			(at -10.020046 22.23008 180)
			(size 0.450088 0.450088)
			(layers "F.Cu" "F.Mask" "F.Paste")
			(net "P5E_CPU0_P2_RX_DN<9>")
		)
		(pad "CL28" smd circle
			(at -9.079992 22.23008 180)
			(size 0.450088 0.450088)
			(layers "F.Cu" "F.Mask" "F.Paste")
			(net "GND")
		)
		(pad "CL29" smd circle
			(at -8.139938 22.23008 180)
			(size 0.450088 0.450088)
			(layers "F.Cu" "F.Mask" "F.Paste")
			(net "PVDDCR_CPU1_P0")
		)
		(pad "CL30" smd circle
			(at -7.199884 22.23008 180)
			(size 0.450088 0.450088)
			(layers "F.Cu" "F.Mask" "F.Paste")
			(net "PVDDCR_CPU1_P0")
		)
		(pad "CL31" smd circle
			(at -6.260084 22.23008 180)
			(size 0.450088 0.450088)
			(layers "F.Cu" "F.Mask" "F.Paste")
			(net "GND")
		)
		(pad "CL32" smd circle
			(at -5.32003 22.23008 180)
			(size 0.450088 0.450088)
			(layers "F.Cu" "F.Mask" "F.Paste")
			(net "PVDDCR_CPU1_P0")
		)
		(pad "CL33" smd circle
			(at -4.379976 22.23008 180)
			(size 0.450088 0.450088)
			(layers "F.Cu" "F.Mask" "F.Paste")
			(net "PVDDCR_CPU1_P0")
		)
		(pad "CL34" smd circle
			(at -3.439922 22.23008 180)
			(size 0.450088 0.450088)
			(layers "F.Cu" "F.Mask" "F.Paste")
			(net "GND")
		)
		(pad "CL35" smd circle
			(at -2.500122 22.23008 180)
			(size 0.450088 0.450088)
			(layers "F.Cu" "F.Mask" "F.Paste")
			(net "GND")
		)
		(pad "CL36" smd circle
			(at -1.560068 22.23008 180)
			(size 0.450088 0.450088)
			(layers "F.Cu" "F.Mask" "F.Paste")
			(net "GND")
		)
		(pad "CL40" smd circle
			(at 1.260094 22.23008 180)
			(size 0.450088 0.450088)
			(layers "F.Cu" "F.Mask" "F.Paste")
			(net "GND")
		)
		(pad "CL41" smd circle
			(at 2.199894 22.23008 180)
			(size 0.450088 0.450088)
			(layers "F.Cu" "F.Mask" "F.Paste")
			(net "GND")
		)
		(pad "CL42" smd circle
			(at 3.139948 22.23008 180)
			(size 0.450088 0.450088)
			(layers "F.Cu" "F.Mask" "F.Paste")
			(net "GND")
		)
		(pad "CL43" smd circle
			(at 4.080002 22.23008 180)
			(size 0.450088 0.450088)
			(layers "F.Cu" "F.Mask" "F.Paste")
			(net "PVDDCR_CPU1_P0")
		)
		(pad "CL44" smd circle
			(at 5.020056 22.23008 180)
			(size 0.450088 0.450088)
			(layers "F.Cu" "F.Mask" "F.Paste")
			(net "PVDDCR_CPU1_P0")
		)
		(pad "CL45" smd circle
			(at 5.96011 22.23008 180)
			(size 0.450088 0.450088)
			(layers "F.Cu" "F.Mask" "F.Paste")
			(net "GND")
		)
		(pad "CL46" smd circle
			(at 6.89991 22.23008 180)
			(size 0.450088 0.450088)
			(layers "F.Cu" "F.Mask" "F.Paste")
			(net "PVDDCR_CPU1_P0")
		)
		(pad "CL47" smd circle
			(at 7.839964 22.23008 180)
			(size 0.450088 0.450088)
			(layers "F.Cu" "F.Mask" "F.Paste")
			(net "PVDDCR_CPU1_P0")
		)
		(pad "CL48" smd circle
			(at 8.780018 22.23008 180)
			(size 0.450088 0.450088)
			(layers "F.Cu" "F.Mask" "F.Paste")
			(net "GND")
		)
		(pad "CL49" smd circle
			(at 9.720072 22.23008 180)
			(size 0.450088 0.450088)
			(layers "F.Cu" "F.Mask" "F.Paste")
			(net "P5E_CPU0_P0_TX_DN<6>")
		)
		(pad "CL50" smd circle
			(at 10.659872 22.23008 180)
			(size 0.450088 0.450088)
			(layers "F.Cu" "F.Mask" "F.Paste")
			(net "P5E_CPU0_P0_TX_DP<6>")
		)
		(pad "CL51" smd circle
			(at 11.599926 22.23008 180)
			(size 0.450088 0.450088)
			(layers "F.Cu" "F.Mask" "F.Paste")
			(net "GND")
		)
		(pad "CL52" smd circle
			(at 12.53998 22.23008 180)
			(size 0.450088 0.450088)
			(layers "F.Cu" "F.Mask" "F.Paste")
			(net "P5E_CPU0_P0_TX_DN<2>")
		)
		(pad "CL53" smd circle
			(at 13.480034 22.23008 180)
			(size 0.450088 0.450088)
			(layers "F.Cu" "F.Mask" "F.Paste")
			(net "P5E_CPU0_P0_TX_DP<2>")
		)
		(pad "CL54" smd circle
			(at 14.420088 22.23008 180)
			(size 0.450088 0.450088)
			(layers "F.Cu" "F.Mask" "F.Paste")
			(net "GND")
		)
		(pad "CL55" smd circle
			(at 15.359888 22.23008 180)
			(size 0.450088 0.450088)
			(layers "F.Cu" "F.Mask" "F.Paste")
			(net "M_C_CPU0_SB_DQS_DN<6>")
		)
		(pad "CL56" smd circle
			(at 16.299942 22.23008 180)
			(size 0.450088 0.450088)
			(layers "F.Cu" "F.Mask" "F.Paste")
			(net "GND")
		)
		(pad "CL57" smd circle
			(at 17.239996 22.23008 180)
			(size 0.450088 0.450088)
			(layers "F.Cu" "F.Mask" "F.Paste")
			(net "M_C_CPU0_SB_DQS_DN<1>")
		)
		(pad "CL58" smd circle
			(at 18.18005 22.23008 180)
			(size 0.450088 0.450088)
			(layers "F.Cu" "F.Mask" "F.Paste")
			(net "GND")
		)
		(pad "CL59" smd circle
			(at 19.120104 22.23008 180)
			(size 0.450088 0.450088)
			(layers "F.Cu" "F.Mask" "F.Paste")
			(net "M_D_CPU0_SB_DQS_DN<6>")
		)
		(pad "CL60" smd circle
			(at 20.059904 22.23008 180)
			(size 0.450088 0.450088)
			(layers "F.Cu" "F.Mask" "F.Paste")
			(net "M_D_CPU0_SB_DQS_DN<1>")
		)
		(pad "CL61" smd circle
			(at 20.999958 22.23008 180)
			(size 0.450088 0.450088)
			(layers "F.Cu" "F.Mask" "F.Paste")
			(net "GND")
		)
		(pad "CL62" smd circle
			(at 21.940012 22.23008 180)
			(size 0.450088 0.450088)
			(layers "F.Cu" "F.Mask" "F.Paste")
			(net "M_B_CPU0_SB_DQS_DN<6>")
		)
		(pad "CL63" smd circle
			(at 22.880066 22.23008 180)
			(size 0.450088 0.450088)
			(layers "F.Cu" "F.Mask" "F.Paste")
			(net "GND")
		)
		(pad "CL64" smd circle
			(at 23.82012 22.23008 180)
			(size 0.450088 0.450088)
			(layers "F.Cu" "F.Mask" "F.Paste")
			(net "M_B_CPU0_SB_DQS_DN<1>")
		)
		(pad "CL65" smd circle
			(at 24.75992 22.23008 180)
			(size 0.450088 0.450088)
			(layers "F.Cu" "F.Mask" "F.Paste")
			(net "GND")
		)
		(pad "CL66" smd circle
			(at 25.699974 22.23008 180)
			(size 0.450088 0.450088)
			(layers "F.Cu" "F.Mask" "F.Paste")
			(net "M_F_CPU0_SB_DQS_DN<6>")
		)
		(pad "CL67" smd circle
			(at 26.640028 22.23008 180)
			(size 0.450088 0.450088)
			(layers "F.Cu" "F.Mask" "F.Paste")
			(net "M_F_CPU0_SB_DQS_DN<1>")
		)
		(pad "CL68" smd circle
			(at 27.580082 22.23008 180)
			(size 0.450088 0.450088)
			(layers "F.Cu" "F.Mask" "F.Paste")
			(net "GND")
		)
		(pad "CL69" smd circle
			(at 28.519882 22.23008 180)
			(size 0.450088 0.450088)
			(layers "F.Cu" "F.Mask" "F.Paste")
			(net "M_E_CPU0_SB_DQS_DN<6>")
		)
		(pad "CL70" smd circle
			(at 29.459936 22.23008 180)
			(size 0.450088 0.450088)
			(layers "F.Cu" "F.Mask" "F.Paste")
			(net "GND")
		)
		(pad "CL71" smd circle
			(at 30.39999 22.23008 180)
			(size 0.450088 0.450088)
			(layers "F.Cu" "F.Mask" "F.Paste")
			(net "M_E_CPU0_SB_DQS_DN<1>")
		)
		(pad "CL72" smd circle
			(at 31.340044 22.23008 180)
			(size 0.450088 0.450088)
			(layers "F.Cu" "F.Mask" "F.Paste")
			(net "GND")
		)
		(pad "CL73" smd circle
			(at 32.280098 22.23008 180)
			(size 0.450088 0.450088)
			(layers "F.Cu" "F.Mask" "F.Paste")
			(net "M_A_CPU0_SB_DQS_DN<6>")
		)
		(pad "CL74" smd circle
			(at 33.219898 22.23008 180)
			(size 0.450088 0.450088)
			(layers "F.Cu" "F.Mask" "F.Paste")
			(net "M_A_CPU0_SB_DQS_DN<1>")
		)
		(pad "CL75" smd circle
			(at 34.159952 22.23008 180)
			(size 0.450088 0.450088)
			(layers "F.Cu" "F.Mask" "F.Paste")
			(net "GND")
		)
		(pad "CM2" smd circle
			(at -33.990026 23.040086 180)
			(size 0.450088 0.450088)
			(layers "F.Cu" "F.Mask" "F.Paste")
			(net "M_G_CPU0_SB_DQ<12>")
		)
		(pad "CM3" smd circle
			(at -33.049972 23.040086 180)
			(size 0.450088 0.450088)
			(layers "F.Cu" "F.Mask" "F.Paste")
			(net "GND")
		)
		(pad "CM4" smd circle
			(at -32.109918 23.040086 180)
			(size 0.450088 0.450088)
			(layers "F.Cu" "F.Mask" "F.Paste")
			(net "M_G_CPU0_SB_DQS_DP<6>")
		)
		(pad "CM5" smd circle
			(at -31.170118 23.040086 180)
			(size 0.450088 0.450088)
			(layers "F.Cu" "F.Mask" "F.Paste")
			(net "GND")
		)
		(pad "CM6" smd circle
			(at -30.230064 23.040086 180)
			(size 0.450088 0.450088)
			(layers "F.Cu" "F.Mask" "F.Paste")
			(net "M_K_CPU0_SB_DQ<12>")
		)
		(pad "CM7" smd circle
			(at -29.29001 23.040086 180)
			(size 0.450088 0.450088)
			(layers "F.Cu" "F.Mask" "F.Paste")
			(net "M_K_CPU0_SB_DQS_DP<6>")
		)
		(pad "CM8" smd circle
			(at -28.349956 23.040086 180)
			(size 0.450088 0.450088)
			(layers "F.Cu" "F.Mask" "F.Paste")
			(net "GND")
		)
		(pad "CM9" smd circle
			(at -27.409902 23.040086 180)
			(size 0.450088 0.450088)
			(layers "F.Cu" "F.Mask" "F.Paste")
			(net "M_L_CPU0_SB_DQ<12>")
		)
		(pad "CM10" smd circle
			(at -26.470102 23.040086 180)
			(size 0.450088 0.450088)
			(layers "F.Cu" "F.Mask" "F.Paste")
			(net "GND")
		)
		(pad "CM11" smd circle
			(at -25.530048 23.040086 180)
			(size 0.450088 0.450088)
			(layers "F.Cu" "F.Mask" "F.Paste")
			(net "M_L_CPU0_SB_DQS_DP<6>")
		)
		(pad "CM12" smd circle
			(at -24.589994 23.040086 180)
			(size 0.450088 0.450088)
			(layers "F.Cu" "F.Mask" "F.Paste")
			(net "GND")
		)
		(pad "CM13" smd circle
			(at -23.64994 23.040086 180)
			(size 0.450088 0.450088)
			(layers "F.Cu" "F.Mask" "F.Paste")
			(net "M_H_CPU0_SB_DQ<12>")
		)
		(pad "CM14" smd circle
			(at -22.709886 23.040086 180)
			(size 0.450088 0.450088)
			(layers "F.Cu" "F.Mask" "F.Paste")
			(net "M_H_CPU0_SB_DQS_DP<6>")
		)
		(pad "CM15" smd circle
			(at -21.770086 23.040086 180)
			(size 0.450088 0.450088)
			(layers "F.Cu" "F.Mask" "F.Paste")
			(net "GND")
		)
		(pad "CM16" smd circle
			(at -20.830032 23.040086 180)
			(size 0.450088 0.450088)
			(layers "F.Cu" "F.Mask" "F.Paste")
			(net "M_J_CPU0_SB_DQ<12>")
		)
		(pad "CM17" smd circle
			(at -19.889978 23.040086 180)
			(size 0.450088 0.450088)
			(layers "F.Cu" "F.Mask" "F.Paste")
			(net "GND")
		)
		(pad "CM18" smd circle
			(at -18.949924 23.040086 180)
			(size 0.450088 0.450088)
			(layers "F.Cu" "F.Mask" "F.Paste")
			(net "M_J_CPU0_SB_DQS_DP<6>")
		)
		(pad "CM19" smd circle
			(at -18.010124 23.040086 180)
			(size 0.450088 0.450088)
			(layers "F.Cu" "F.Mask" "F.Paste")
			(net "GND")
		)
		(pad "CM20" smd circle
			(at -17.07007 23.040086 180)
			(size 0.450088 0.450088)
			(layers "F.Cu" "F.Mask" "F.Paste")
			(net "M_I_CPU0_SB_DQ<12>")
		)
		(pad "CM21" smd circle
			(at -16.130016 23.040086 180)
			(size 0.450088 0.450088)
			(layers "F.Cu" "F.Mask" "F.Paste")
			(net "M_I_CPU0_SB_DQS_DP<6>")
		)
		(pad "CM22" smd circle
			(at -15.189962 23.040086 180)
			(size 0.450088 0.450088)
			(layers "F.Cu" "F.Mask" "F.Paste")
			(net "PVDD11_S3_P0")
		)
		(pad "CM23" smd circle
			(at -14.249908 23.040086 180)
			(size 0.450088 0.450088)
			(layers "F.Cu" "F.Mask" "F.Paste")
			(net "GND")
		)
		(pad "CM24" smd circle
			(at -13.310108 23.040086 180)
			(size 0.450088 0.450088)
			(layers "F.Cu" "F.Mask" "F.Paste")
			(net "GND")
		)
		(pad "CM25" smd circle
			(at -12.370054 23.040086 180)
			(size 0.450088 0.450088)
			(layers "F.Cu" "F.Mask" "F.Paste")
			(net "GND")
		)
		(pad "CM26" smd circle
			(at -11.43 23.040086 180)
			(size 0.450088 0.450088)
			(layers "F.Cu" "F.Mask" "F.Paste")
			(net "GND")
		)
		(pad "CM27" smd circle
			(at -10.489946 23.040086 180)
			(size 0.450088 0.450088)
			(layers "F.Cu" "F.Mask" "F.Paste")
			(net "GND")
		)
		(pad "CM28" smd circle
			(at -9.549892 23.040086 180)
			(size 0.450088 0.450088)
			(layers "F.Cu" "F.Mask" "F.Paste")
			(net "GND")
		)
		(pad "CM29" smd circle
			(at -8.610092 23.040086 180)
			(size 0.450088 0.450088)
			(layers "F.Cu" "F.Mask" "F.Paste")
			(net "GND")
		)
		(pad "CM30" smd circle
			(at -7.670038 23.040086 180)
			(size 0.450088 0.450088)
			(layers "F.Cu" "F.Mask" "F.Paste")
			(net "GND")
		)
		(pad "CM31" smd circle
			(at -6.729984 23.040086 180)
			(size 0.450088 0.450088)
			(layers "F.Cu" "F.Mask" "F.Paste")
			(net "GND")
		)
		(pad "CM32" smd circle
			(at -5.78993 23.040086 180)
			(size 0.450088 0.450088)
			(layers "F.Cu" "F.Mask" "F.Paste")
			(net "GND")
		)
		(pad "CM33" smd circle
			(at -4.849876 23.040086 180)
			(size 0.450088 0.450088)
			(layers "F.Cu" "F.Mask" "F.Paste")
			(net "GND")
		)
		(pad "CM34" smd circle
			(at -3.910076 23.040086 180)
			(size 0.450088 0.450088)
			(layers "F.Cu" "F.Mask" "F.Paste")
			(net "GND")
		)
		(pad "CM35" smd circle
			(at -2.970022 23.040086 180)
			(size 0.450088 0.450088)
			(layers "F.Cu" "F.Mask" "F.Paste")
			(net "P5E_CPU0_P2_RX_DP<0>")
		)
		(pad "CM36" smd circle
			(at -2.029968 23.040086 180)
			(size 0.450088 0.450088)
			(layers "F.Cu" "F.Mask" "F.Paste")
			(net "P5E_CPU0_P2_RX_DN<0>")
		)
		(pad "CM37" smd circle
			(at -1.089914 23.040086 180)
			(size 0.450088 0.450088)
			(layers "F.Cu" "F.Mask" "F.Paste")
			(net "GND")
		)
		(pad "CM39" smd circle
			(at 0.78994 23.040086 180)
			(size 0.450088 0.450088)
			(layers "F.Cu" "F.Mask" "F.Paste")
			(net "GND")
		)
		(pad "CM40" smd circle
			(at 1.729994 23.040086 180)
			(size 0.450088 0.450088)
			(layers "F.Cu" "F.Mask" "F.Paste")
			(net "P5E_CPU0_P0_TX_DN<15>")
		)
		(pad "CM41" smd circle
			(at 2.670048 23.040086 180)
			(size 0.450088 0.450088)
			(layers "F.Cu" "F.Mask" "F.Paste")
			(net "P5E_CPU0_P0_TX_DP<15>")
		)
		(pad "CM42" smd circle
			(at 3.610102 23.040086 180)
			(size 0.450088 0.450088)
			(layers "F.Cu" "F.Mask" "F.Paste")
			(net "GND")
		)
		(pad "CM43" smd circle
			(at 4.549902 23.040086 180)
			(size 0.450088 0.450088)
			(layers "F.Cu" "F.Mask" "F.Paste")
			(net "GND")
		)
		(pad "CM44" smd circle
			(at 5.489956 23.040086 180)
			(size 0.450088 0.450088)
			(layers "F.Cu" "F.Mask" "F.Paste")
			(net "GND")
		)
		(pad "CM45" smd circle
			(at 6.43001 23.040086 180)
			(size 0.450088 0.450088)
			(layers "F.Cu" "F.Mask" "F.Paste")
			(net "GND")
		)
		(pad "CM46" smd circle
			(at 7.370064 23.040086 180)
			(size 0.450088 0.450088)
			(layers "F.Cu" "F.Mask" "F.Paste")
			(net "GND")
		)
		(pad "CM47" smd circle
			(at 8.310118 23.040086 180)
			(size 0.450088 0.450088)
			(layers "F.Cu" "F.Mask" "F.Paste")
			(net "GND")
		)
		(pad "CM48" smd circle
			(at 9.249918 23.040086 180)
			(size 0.450088 0.450088)
			(layers "F.Cu" "F.Mask" "F.Paste")
			(net "GND")
		)
		(pad "CM49" smd circle
			(at 10.189972 23.040086 180)
			(size 0.450088 0.450088)
			(layers "F.Cu" "F.Mask" "F.Paste")
			(net "GND")
		)
		(pad "CM50" smd circle
			(at 11.130026 23.040086 180)
			(size 0.450088 0.450088)
			(layers "F.Cu" "F.Mask" "F.Paste")
			(net "GND")
		)
		(pad "CM51" smd circle
			(at 12.07008 23.040086 180)
			(size 0.450088 0.450088)
			(layers "F.Cu" "F.Mask" "F.Paste")
			(net "GND")
		)
		(pad "CM52" smd circle
			(at 13.00988 23.040086 180)
			(size 0.450088 0.450088)
			(layers "F.Cu" "F.Mask" "F.Paste")
			(net "GND")
		)
		(pad "CM53" smd circle
			(at 13.949934 23.040086 180)
			(size 0.450088 0.450088)
			(layers "F.Cu" "F.Mask" "F.Paste")
			(net "GND")
		)
		(pad "CM54" smd circle
			(at 14.889988 23.040086 180)
			(size 0.450088 0.450088)
			(layers "F.Cu" "F.Mask" "F.Paste")
			(net "PVDDIO_P0")
		)
		(pad "CM55" smd circle
			(at 15.830042 23.040086 180)
			(size 0.450088 0.450088)
			(layers "F.Cu" "F.Mask" "F.Paste")
			(net "M_C_CPU0_SB_DQS_DP<6>")
		)
		(pad "CM56" smd circle
			(at 16.770096 23.040086 180)
			(size 0.450088 0.450088)
			(layers "F.Cu" "F.Mask" "F.Paste")
			(net "M_C_CPU0_SB_DQ<12>")
		)
		(pad "CM57" smd circle
			(at 17.709896 23.040086 180)
			(size 0.450088 0.450088)
			(layers "F.Cu" "F.Mask" "F.Paste")
			(net "GND")
		)
		(pad "CM58" smd circle
			(at 18.64995 23.040086 180)
			(size 0.450088 0.450088)
			(layers "F.Cu" "F.Mask" "F.Paste")
			(net "M_D_CPU0_SB_DQS_DP<6>")
		)
		(pad "CM59" smd circle
			(at 19.590004 23.040086 180)
			(size 0.450088 0.450088)
			(layers "F.Cu" "F.Mask" "F.Paste")
			(net "GND")
		)
		(pad "CM60" smd circle
			(at 20.530058 23.040086 180)
			(size 0.450088 0.450088)
			(layers "F.Cu" "F.Mask" "F.Paste")
			(net "M_D_CPU0_SB_DQ<12>")
		)
		(pad "CM61" smd circle
			(at 21.470112 23.040086 180)
			(size 0.450088 0.450088)
			(layers "F.Cu" "F.Mask" "F.Paste")
			(net "GND")
		)
		(pad "CM62" smd circle
			(at 22.409912 23.040086 180)
			(size 0.450088 0.450088)
			(layers "F.Cu" "F.Mask" "F.Paste")
			(net "M_B_CPU0_SB_DQS_DP<6>")
		)
		(pad "CM63" smd circle
			(at 23.349966 23.040086 180)
			(size 0.450088 0.450088)
			(layers "F.Cu" "F.Mask" "F.Paste")
			(net "M_B_CPU0_SB_DQ<12>")
		)
		(pad "CM64" smd circle
			(at 24.29002 23.040086 180)
			(size 0.450088 0.450088)
			(layers "F.Cu" "F.Mask" "F.Paste")
			(net "GND")
		)
		(pad "CM65" smd circle
			(at 25.230074 23.040086 180)
			(size 0.450088 0.450088)
			(layers "F.Cu" "F.Mask" "F.Paste")
			(net "M_F_CPU0_SB_DQS_DP<6>")
		)
		(pad "CM66" smd circle
			(at 26.170128 23.040086 180)
			(size 0.450088 0.450088)
			(layers "F.Cu" "F.Mask" "F.Paste")
			(net "GND")
		)
		(pad "CM67" smd circle
			(at 27.109928 23.040086 180)
			(size 0.450088 0.450088)
			(layers "F.Cu" "F.Mask" "F.Paste")
			(net "M_F_CPU0_SB_DQ<12>")
		)
		(pad "CM68" smd circle
			(at 28.049982 23.040086 180)
			(size 0.450088 0.450088)
			(layers "F.Cu" "F.Mask" "F.Paste")
			(net "GND")
		)
		(pad "CM69" smd circle
			(at 28.990036 23.040086 180)
			(size 0.450088 0.450088)
			(layers "F.Cu" "F.Mask" "F.Paste")
			(net "M_E_CPU0_SB_DQS_DP<6>")
		)
	)
)
